#ISCELL
  pure_quanta quanta_title_block_c *
  *
#CELL
  pure_quanta pt5161lrs *
  page448_i1
#ISCELL
  standard tap *
  page448_i10
#ISCELL
  standard tap *
  page448_i11
#ISCELL
  standard tap *
  page448_i12
#ISCELL
  standard tap *
  page448_i13
#ISCELL
  standard tap *
  page448_i14
#ISCELL
  standard tap *
  page448_i15
#ISCELL
  standard tap *
  page448_i16
#ISCELL
  standard tap *
  page448_i17
#ISCELL
  standard offpage *
  page448_i18
#ISCELL
  standard offpage *
  page448_i19
#ISCELL
  standard tap *
  page448_i2
#ISCELL
  standard tap *
  page448_i20
#ISCELL
  standard tap *
  page448_i21
#ISCELL
  standard tap *
  page448_i22
#ISCELL
  standard tap *
  page448_i23
#ISCELL
  standard tap *
  page448_i24
#ISCELL
  standard tap *
  page448_i25
#ISCELL
  standard tap *
  page448_i26
#ISCELL
  standard tap *
  page448_i27
#ISCELL
  standard tap *
  page448_i28
#ISCELL
  standard tap *
  page448_i29
#ISCELL
  standard tap *
  page448_i3
#ISCELL
  standard tap *
  page448_i30
#ISCELL
  standard tap *
  page448_i31
#ISCELL
  standard tap *
  page448_i32
#ISCELL
  standard tap *
  page448_i33
#ISCELL
  standard tap *
  page448_i34
#ISCELL
  standard offpage *
  page448_i35
#ISCELL
  standard offpage *
  page448_i36
#ISCELL
  standard tap *
  page448_i37
#CELL
  pure_quanta pt5161lrs *
  page448_i38
#ISCELL
  standard tap *
  page448_i4
#ISCELL
  standard tap *
  page448_i5
#ISCELL
  standard tap *
  page448_i6
#ISCELL
  standard tap *
  page448_i7
#ISCELL
  standard tap *
  page448_i8
#ISCELL
  standard tap *
  page448_i9
